(kicad_pcb
	(version 20241229)
	(generator "pcbnew")
	(generator_version "9.0")
	(general
		(thickness 1.711)
		(legacy_teardrops no)
	)
	(paper "A4")
	(title_block
		(title "Antmicro Baseboard for Jetson AGX Thor")
		(date "2026-02-18")
		(rev "1.1.0")
		(company "Antmicro Ltd")
		(comment 1 "www.antmicro.com")
		(comment 9 "footprint 110 of 1170 (J1), pads 485-564 of 699")
	)
	(layers
		(0 "F.Cu" signal)
		(4 "In1.Cu" signal)
		(6 "In2.Cu" signal)
		(8 "In3.Cu" signal)
		(10 "In4.Cu" jumper)
		(12 "In5.Cu" signal)
		(14 "In6.Cu" signal)
		(16 "In7.Cu" signal)
		(18 "In8.Cu" signal)
		(2 "B.Cu" signal)
		(9 "F.Adhes" user "F.Adhesive")
		(11 "B.Adhes" user "B.Adhesive")
		(13 "F.Paste" user)
		(15 "B.Paste" user)
		(5 "F.SilkS" user "F.Silkscreen")
		(7 "B.SilkS" user "B.Silkscreen")
		(1 "F.Mask" user)
		(3 "B.Mask" user)
		(17 "Dwgs.User" user "User.Drawings")
		(19 "Cmts.User" user "User.Comments")
		(21 "Eco1.User" user "User.Eco1")
		(23 "Eco2.User" user "User.Eco2")
		(25 "Edge.Cuts" user)
		(27 "Margin" user)
		(31 "F.CrtYd" user "F.Courtyard")
		(29 "B.CrtYd" user "B.Courtyard")
		(35 "F.Fab" user)
		(33 "B.Fab" user)
	)
	(footprint "antmicro-footprints:Conn_Hermaphroditic_Molex_203456-0003_mirrored"
		(locked yes)
		(layer "F.Cu")
		(at 116.530532 78.15)
		(descr "Mirrored version of: https://www.molex.com/content/dam/molex/molex-dot-com/products/automated/en-us/salesdrawingpdf/203/203456/2034560003_sd.pdf")
		(property "Reference" "J1"
			(at -32.25 -11.2 180)
			(layer "F.SilkS")
			(effects
				(font
					(size 0.7 0.7)
					(thickness 0.15)
				)
				(justify right top)
			)
		)
		(property "Value" "Hermaphroditic_Molex_203456-0003_CUSTOM_Jetson_AGX_Thor_H8mm"
			(at 0.1 12.9 0)
			(layer "F.Fab")
			(effects
				(font
					(size 0.7 0.7)
					(thickness 0.15)
				)
				(justify right top)
			)
		)
		(property "Datasheet" "https://www.molex.com/content/dam/molex/molex-dot-com/products/automated/en-us/salesdrawingpdf/203/203456/2034560003_sd.pdf?inline"
			(at 0.1 0.2 0)
			(layer "F.Fab")
			(hide yes)
			(effects
				(font
					(size 0.7 0.7)
					(thickness 0.15)
				)
				(justify right top)
			)
		)
		(property "Description" "Mirror Mezz Hermaphroditic Connector, 5.50mm Connector Height, BGA-Attach Mounting, 7 Pair, 11 Row, 699 Circuits, 0.76µm Gold Plating, without Pegs"
			(at 0.1 0.2 0)
			(layer "F.Fab")
			(hide yes)
			(effects
				(font
					(size 0.7 0.7)
					(thickness 0.15)
				)
				(justify right top)
			)
		)
		(property "MPN" "203456-0003"
			(at 0 0 0)
			(unlocked yes)
			(layer "F.Fab")
			(hide yes)
			(effects
				(font
					(size 1 1)
					(thickness 0.15)
				)
			)
		)
		(property "Manufacturer" "Molex"
			(at 0 0 0)
			(unlocked yes)
			(layer "F.Fab")
			(hide yes)
			(effects
				(font
					(size 1 1)
					(thickness 0.15)
				)
			)
		)
		(property "Author" "Antmicro"
			(at 0 0 0)
			(unlocked yes)
			(layer "F.Fab")
			(hide yes)
			(effects
				(font
					(size 1 1)
					(thickness 0.15)
				)
			)
		)
		(property "License" "Apache-2.0"
			(at 0 0 0)
			(unlocked yes)
			(layer "F.Fab")
			(hide yes)
			(effects
				(font
					(size 1 1)
					(thickness 0.15)
				)
			)
		)
		(sheetname "/SoM_IO/")
		(sheetfile "som_io.kicad_sch")
		(solder_mask_margin 0.05)
		(attr smd)
		(pad "H38" smd circle
			(at 5.7 -3 90)
			(size 0.5 0.5)
			(layers "F.Cu" "F.Mask" "F.Paste")
			(net 1 "GND")
			(pinfunction "GND")
			(pintype "passive")
		)
		(pad "H39" smd circle
			(at 7 -3 90)
			(size 0.5 0.5)
			(layers "F.Cu" "F.Mask" "F.Paste")
			(net 1 "GND")
			(pinfunction "GND")
			(pintype "passive")
		)
		(pad "H40" smd circle
			(at 7.9 -3 90)
			(size 0.5 0.5)
			(layers "F.Cu" "F.Mask" "F.Paste")
			(net 99 "unconnected-(J1A-MID1-PadH40)")
			(pinfunction "MID1")
			(pintype "passive+no_connect")
		)
		(pad "H41" smd circle
			(at 8.8 -3 90)
			(size 0.5 0.5)
			(layers "F.Cu" "F.Mask" "F.Paste")
			(net 1 "GND")
			(pinfunction "GND")
			(pintype "passive")
		)
		(pad "H42" smd circle
			(at 9.7 -3 90)
			(size 0.5 0.5)
			(layers "F.Cu" "F.Mask" "F.Paste")
			(net 83 "unconnected-(J1F-CSI1_CLK_N-PadH42)")
			(pinfunction "CSI1_CLK_N")
			(pintype "input+no_connect")
		)
		(pad "H43" smd circle
			(at 10.6 -3 90)
			(size 0.5 0.5)
			(layers "F.Cu" "F.Mask" "F.Paste")
			(net 159 "unconnected-(J1F-CSI1_CLK_P-PadH43)")
			(pinfunction "CSI1_CLK_P")
			(pintype "input+no_connect")
		)
		(pad "H44" smd circle
			(at 11.5 -3 90)
			(size 0.5 0.5)
			(layers "F.Cu" "F.Mask" "F.Paste")
			(net 1 "GND")
			(pinfunction "GND")
			(pintype "passive")
		)
		(pad "H45" smd circle
			(at 12.4 -3 90)
			(size 0.5 0.5)
			(layers "F.Cu" "F.Mask" "F.Paste")
			(net 62 "/CSI/CAM3.CSI6_D1-")
			(pinfunction "CSI6_D1_N")
			(pintype "input")
		)
		(pad "H46" smd circle
			(at 13.3 -3 90)
			(size 0.5 0.5)
			(layers "F.Cu" "F.Mask" "F.Paste")
			(net 70 "/CSI/CAM3.CSI6_D1+")
			(pinfunction "CSI6_D1_P")
			(pintype "input")
		)
		(pad "H47" smd circle
			(at 14.2 -3 90)
			(size 0.5 0.5)
			(layers "F.Cu" "F.Mask" "F.Paste")
			(net 1 "GND")
			(pinfunction "GND")
			(pintype "passive")
		)
		(pad "H48" smd circle
			(at 15.1 -3 90)
			(size 0.5 0.5)
			(layers "F.Cu" "F.Mask" "F.Paste")
			(net 1248 "/SoM_IO2/DP1.TX0_C-")
			(pinfunction "DP1_D0_HDMI_D2_N")
			(pintype "output")
		)
		(pad "H49" smd circle
			(at 16 -3 90)
			(size 0.5 0.5)
			(layers "F.Cu" "F.Mask" "F.Paste")
			(net 1191 "/SoM_IO2/DP1.TX0_C+")
			(pinfunction "DP1_D0_HDMI_D2_P")
			(pintype "output")
		)
		(pad "H50" smd circle
			(at 16.9 -3 90)
			(size 0.5 0.5)
			(layers "F.Cu" "F.Mask" "F.Paste")
			(net 1 "GND")
			(pinfunction "GND")
			(pintype "passive")
		)
		(pad "H51" smd circle
			(at 17.8 -3 90)
			(size 0.5 0.5)
			(layers "F.Cu" "F.Mask" "F.Paste")
			(net 899 "unconnected-(J1C-GPIO26-PadH51)")
			(pinfunction "GPIO26")
			(pintype "passive+no_connect")
		)
		(pad "H52" smd circle
			(at 18.7 -3 90)
			(size 0.5 0.5)
			(layers "F.Cu" "F.Mask" "F.Paste")
			(net 319 "/Expansion connector/FMC_PRSNT_M2C_L")
			(pinfunction "GPIO27")
			(pintype "passive")
		)
		(pad "H53" smd circle
			(at 19.6 -3 90)
			(size 0.5 0.5)
			(layers "F.Cu" "F.Mask" "F.Paste")
			(net 321 "/Expansion connector/GPIO.MCLK03")
			(pinfunction "MCLK03")
			(pintype "passive")
		)
		(pad "H54" smd circle
			(at 20.5 -3 90)
			(size 0.5 0.5)
			(layers "F.Cu" "F.Mask" "F.Paste")
			(net 243 "/SoM_IO/UART1.CTS")
			(pinfunction "UART1_CTS")
			(pintype "input")
		)
		(pad "H55" smd circle
			(at 21.4 -3 90)
			(size 0.5 0.5)
			(layers "F.Cu" "F.Mask" "F.Paste")
			(net 555 "unconnected-(J1D-MCLK04-PadH55)")
			(pinfunction "MCLK04")
			(pintype "bidirectional+no_connect")
		)
		(pad "H56" smd circle
			(at 22.3 -3 90)
			(size 0.5 0.5)
			(layers "F.Cu" "F.Mask" "F.Paste")
			(net 1 "GND")
			(pinfunction "GND")
			(pintype "passive")
		)
		(pad "H57" smd circle
			(at 23.2 -3 90)
			(size 0.5 0.5)
			(layers "F.Cu" "F.Mask" "F.Paste")
			(net 121 "/Expansion connector/UART5.CTS")
			(pinfunction "UART5_CTS")
			(pintype "input")
		)
		(pad "H58" smd circle
			(at 24.1 -3 90)
			(size 0.5 0.5)
			(layers "F.Cu" "F.Mask" "F.Paste")
			(net 151 "/Expansion connector/UART5.RX")
			(pinfunction "UART5_RX")
			(pintype "input")
		)
		(pad "H59" smd circle
			(at 25 -3 90)
			(size 0.5 0.5)
			(layers "F.Cu" "F.Mask" "F.Paste")
			(net 606 "/SoM_IO2/NVJTAG_SEL")
			(pinfunction "NVJTAG_SEL")
			(pintype "passive")
		)
		(pad "H60" smd circle
			(at 25.9 -3 90)
			(size 0.5 0.5)
			(layers "F.Cu" "F.Mask" "F.Paste")
			(net 758 "Net-(J1A-GPIO31)")
			(pinfunction "GPIO31")
			(pintype "passive")
		)
		(pad "H61" smd circle
			(at 26.8 -3 90)
			(size 0.5 0.5)
			(layers "F.Cu" "F.Mask" "F.Paste")
			(net 783 "/Expansion connector/CAN3.DOUT")
			(pinfunction "CAN3_DOUT")
			(pintype "output")
		)
		(pad "H62" smd circle
			(at 27.7 -3 90)
			(size 0.5 0.5)
			(layers "F.Cu" "F.Mask" "F.Paste")
			(net 496 "/SoM_IO/UART3_DEBUG_TX_1V8")
			(pinfunction "UART3_TX_DEBUG")
			(pintype "output")
		)
		(pad "H63" smd circle
			(at 28.6 -3 90)
			(size 0.5 0.5)
			(layers "F.Cu" "F.Mask" "F.Paste")
			(net 1 "GND")
			(pinfunction "GND")
			(pintype "passive")
		)
		(pad "H64" smd circle
			(at 29.5 -3 90)
			(size 0.5 0.5)
			(layers "F.Cu" "F.Mask" "F.Paste")
			(net 12 "SYS_VIN_HV")
			(pinfunction "SYS_VIN_HV")
			(pintype "passive")
		)
		(pad "H65" smd circle
			(at 30.4 -3 90)
			(size 0.5 0.5)
			(layers "F.Cu" "F.Mask" "F.Paste")
			(net 12 "SYS_VIN_HV")
			(pinfunction "SYS_VIN_HV")
			(pintype "passive")
		)
		(pad "J1" smd circle
			(at -30.2 -4.5 90)
			(size 0.5 0.5)
			(layers "F.Cu" "F.Mask" "F.Paste")
			(net 12 "SYS_VIN_HV")
			(pinfunction "SYS_VIN_HV")
			(pintype "passive")
		)
		(pad "J2" smd circle
			(at -29.3 -4.5 90)
			(size 0.5 0.5)
			(layers "F.Cu" "F.Mask" "F.Paste")
			(net 12 "SYS_VIN_HV")
			(pinfunction "SYS_VIN_HV")
			(pintype "passive")
		)
		(pad "J3" smd circle
			(at -28.4 -4.5 90)
			(size 0.5 0.5)
			(layers "F.Cu" "F.Mask" "F.Paste")
			(net 1 "GND")
			(pinfunction "GND")
			(pintype "passive")
		)
		(pad "J4" smd circle
			(at -27.5 -4.5 90)
			(size 0.5 0.5)
			(layers "F.Cu" "F.Mask" "F.Paste")
			(net 330 "/Expansion connector/FMC_PG_M2C")
			(pinfunction "GPIO01")
			(pintype "passive")
		)
		(pad "J5" smd circle
			(at -26.6 -4.5 90)
			(size 0.5 0.5)
			(layers "F.Cu" "F.Mask" "F.Paste")
			(net 861 "/Expansion connector/GPIO.27")
			(pinfunction "GPIO63")
			(pintype "passive")
		)
		(pad "J6" smd circle
			(at -25.7 -4.5 90)
			(size 0.5 0.5)
			(layers "F.Cu" "F.Mask" "F.Paste")
			(net 1244 "/SoM_IO/USBC2_VBUS_DET_1V8")
			(pinfunction "GPIO64")
			(pintype "passive")
		)
		(pad "J7" smd circle
			(at -24.8 -4.5 90)
			(size 0.5 0.5)
			(layers "F.Cu" "F.Mask" "F.Paste")
			(net 780 "/SoM_IO/~{PDC_I2C1_IRQ}_1V8")
			(pinfunction "GPIO65")
			(pintype "passive")
		)
		(pad "J8" smd circle
			(at -23.9 -4.5 90)
			(size 0.5 0.5)
			(layers "F.Cu" "F.Mask" "F.Paste")
			(net 1 "GND")
			(pinfunction "GND")
			(pintype "passive")
		)
		(pad "J9" smd circle
			(at -23 -4.5 90)
			(size 0.5 0.5)
			(layers "F.Cu" "F.Mask" "F.Paste")
			(net 569 "/Expansion connector/PCIe_{C3x2}.~{RST}")
			(pinfunction "PEX_C3_RST_N")
			(pintype "output")
		)
		(pad "J10" smd circle
			(at -22.1 -4.5 90)
			(size 0.5 0.5)
			(layers "F.Cu" "F.Mask" "F.Paste")
			(net 755 "unconnected-(J1G-FSI_GPIO21-PadJ10)")
			(pinfunction "FSI_GPIO21")
			(pintype "passive+no_connect")
		)
		(pad "J11" smd circle
			(at -21.2 -4.5 90)
			(size 0.5 0.5)
			(layers "F.Cu" "F.Mask" "F.Paste")
			(net 314 "unconnected-(J1D-FSI_GPIO29-PadJ11)")
			(pinfunction "FSI_GPIO29")
			(pintype "passive+no_connect")
		)
		(pad "J12" smd circle
			(at -20.3 -4.5 90)
			(size 0.5 0.5)
			(layers "F.Cu" "F.Mask" "F.Paste")
			(net 1 "GND")
			(pinfunction "GND")
			(pintype "passive")
		)
		(pad "J13" smd circle
			(at -19 -4.5 90)
			(size 0.5 0.5)
			(layers "F.Cu" "F.Mask" "F.Paste")
			(net 1 "GND")
			(pinfunction "GND")
			(pintype "passive")
		)
		(pad "J14" smd circle
			(at -18.1 -4.5 90)
			(size 0.5 0.5)
			(layers "F.Cu" "F.Mask" "F.Paste")
			(net 1255 "/SoM_IO2/DP2.TX1_C+")
			(pinfunction "DP2_D1_HDMI_D1_P")
			(pintype "output")
		)
		(pad "J15" smd circle
			(at -17.2 -4.5 90)
			(size 0.5 0.5)
			(layers "F.Cu" "F.Mask" "F.Paste")
			(net 1259 "/SoM_IO2/DP2.TX1_C-")
			(pinfunction "DP2_D1_HDMI_D1_N")
			(pintype "output")
		)
		(pad "J16" smd circle
			(at -16.3 -4.5 90)
			(size 0.5 0.5)
			(layers "F.Cu" "F.Mask" "F.Paste")
			(net 1 "GND")
			(pinfunction "GND")
			(pintype "passive")
		)
		(pad "J17" smd circle
			(at -15 -4.5 90)
			(size 0.5 0.5)
			(layers "F.Cu" "F.Mask" "F.Paste")
			(net 1 "GND")
			(pinfunction "GND")
			(pintype "passive")
		)
		(pad "J18" smd circle
			(at -14.1 -4.5 90)
			(size 0.5 0.5)
			(layers "F.Cu" "F.Mask" "F.Paste")
			(net 849 "/Expansion connector/GPIO.18")
			(pinfunction "GPIO50")
			(pintype "passive")
		)
		(pad "J19" smd circle
			(at -13.2 -4.5 90)
			(size 0.5 0.5)
			(layers "F.Cu" "F.Mask" "F.Paste")
			(net 1294 "unconnected-(J1K-GPIO67-PadJ19)")
			(pinfunction "GPIO67")
			(pintype "passive+no_connect")
		)
		(pad "J20" smd circle
			(at -12.3 -4.5 90)
			(size 0.5 0.5)
			(layers "F.Cu" "F.Mask" "F.Paste")
			(net 1 "GND")
			(pinfunction "GND")
			(pintype "passive")
		)
		(pad "J21" smd circle
			(at -11 -4.5 90)
			(size 0.5 0.5)
			(layers "F.Cu" "F.Mask" "F.Paste")
			(net 1 "GND")
			(pinfunction "GND")
			(pintype "passive")
		)
		(pad "J22" smd circle
			(at -10.1 -4.5 90)
			(size 0.5 0.5)
			(layers "F.Cu" "F.Mask" "F.Paste")
			(net 311 "/SoM_IO2/USBSS1.TX+")
			(pinfunction "UPHY_TX1_P")
			(pintype "output")
		)
		(pad "J23" smd circle
			(at -9.2 -4.5 90)
			(size 0.5 0.5)
			(layers "F.Cu" "F.Mask" "F.Paste")
			(net 329 "/SoM_IO2/USBSS1.TX-")
			(pinfunction "UPHY_TX1_N")
			(pintype "output")
		)
		(pad "J24" smd circle
			(at -8.3 -4.5 90)
			(size 0.5 0.5)
			(layers "F.Cu" "F.Mask" "F.Paste")
			(net 1 "GND")
			(pinfunction "GND")
			(pintype "passive")
		)
		(pad "J25" smd circle
			(at -7 -4.5 90)
			(size 0.5 0.5)
			(layers "F.Cu" "F.Mask" "F.Paste")
			(net 1 "GND")
			(pinfunction "GND")
			(pintype "passive")
		)
		(pad "J26" smd circle
			(at -6.1 -4.5 90)
			(size 0.5 0.5)
			(layers "F.Cu" "F.Mask" "F.Paste")
			(net 410 "/M.2/PCIe_{C5x4}.TX3+")
			(pinfunction "UPHY_TX11_P")
			(pintype "output")
		)
		(pad "J27" smd circle
			(at -5.2 -4.5 90)
			(size 0.5 0.5)
			(layers "F.Cu" "F.Mask" "F.Paste")
			(net 439 "/M.2/PCIe_{C5x4}.TX3-")
			(pinfunction "UPHY_TX11_N")
			(pintype "output")
		)
		(pad "J28" smd circle
			(at -4.3 -4.5 90)
			(size 0.5 0.5)
			(layers "F.Cu" "F.Mask" "F.Paste")
			(net 1 "GND")
			(pinfunction "GND")
			(pintype "passive")
		)
		(pad "J29" smd circle
			(at -3 -4.5 90)
			(size 0.5 0.5)
			(layers "F.Cu" "F.Mask" "F.Paste")
			(net 1 "GND")
			(pinfunction "GND")
			(pintype "passive")
		)
		(pad "J30" smd circle
			(at -2.1 -4.5 90)
			(size 0.5 0.5)
			(layers "F.Cu" "F.Mask" "F.Paste")
			(net 582 "unconnected-(J1B-UPHY_TX15_P-PadJ30)")
			(pinfunction "UPHY_TX15_P")
			(pintype "output+no_connect")
		)
		(pad "J31" smd circle
			(at -1.2 -4.5 90)
			(size 0.5 0.5)
			(layers "F.Cu" "F.Mask" "F.Paste")
			(net 581 "unconnected-(J1B-UPHY_TX15_N-PadJ31)")
			(pinfunction "UPHY_TX15_N")
			(pintype "output+no_connect")
		)
		(pad "J32" smd circle
			(at -0.3 -4.5 90)
			(size 0.5 0.5)
			(layers "F.Cu" "F.Mask" "F.Paste")
			(net 1 "GND")
			(pinfunction "GND")
			(pintype "passive")
		)
		(pad "J33" smd circle
			(at 1 -4.5 90)
			(size 0.5 0.5)
			(layers "F.Cu" "F.Mask" "F.Paste")
			(net 1 "GND")
			(pinfunction "GND")
			(pintype "passive")
		)
		(pad "J34" smd circle
			(at 1.9 -4.5 90)
			(size 0.5 0.5)
			(layers "F.Cu" "F.Mask" "F.Paste")
			(net 1269 "/SoM_IO2/DP3.TX1_C-")
			(pinfunction "DP3_D1_HDMI_D1_N")
			(pintype "output")
		)
		(pad "J35" smd circle
			(at 2.8 -4.5 90)
			(size 0.5 0.5)
			(layers "F.Cu" "F.Mask" "F.Paste")
			(net 1265 "/SoM_IO2/DP3.TX1_C+")
			(pinfunction "DP3_D1_HDMI_D1_P")
			(pintype "output")
		)
		(pad "J36" smd circle
			(at 3.7 -4.5 90)
			(size 0.5 0.5)
			(layers "F.Cu" "F.Mask" "F.Paste")
			(net 1 "GND")
			(pinfunction "GND")
			(pintype "passive")
		)
		(pad "J37" smd circle
			(at 5 -4.5 90)
			(size 0.5 0.5)
			(layers "F.Cu" "F.Mask" "F.Paste")
			(net 1 "GND")
			(pinfunction "GND")
			(pintype "passive")
		)
		(pad "J38" smd circle
			(at 5.9 -4.5 90)
			(size 0.5 0.5)
			(layers "F.Cu" "F.Mask" "F.Paste")
			(net 779 "unconnected-(J1G-FSI_GPIO05-PadJ38)")
			(pinfunction "FSI_GPIO05")
			(pintype "passive+no_connect")
		)
		(pad "J39" smd circle
			(at 6.8 -4.5 90)
			(size 0.5 0.5)
			(layers "F.Cu" "F.Mask" "F.Paste")
			(net 774 "unconnected-(J1G-FSI_GPIO06-PadJ39)")
			(pinfunction "FSI_GPIO06")
			(pintype "passive+no_connect")
		)
		(pad "J40" smd circle
			(at 7.7 -4.5 90)
			(size 0.5 0.5)
			(layers "F.Cu" "F.Mask" "F.Paste")
			(net 1 "GND")
			(pinfunction "GND")
			(pintype "passive")
		)
		(pad "J41" smd circle
			(at 8.6 -4.5 90)
			(size 0.5 0.5)
			(layers "F.Cu" "F.Mask" "F.Paste")
			(net 93 "/CSI/CAM1.CSI1_D1+")
			(pinfunction "CSI1_D1_P")
			(pintype "input")
		)
		(pad "J42" smd circle
			(at 9.5 -4.5 90)
			(size 0.5 0.5)
			(layers "F.Cu" "F.Mask" "F.Paste")
			(net 143 "/CSI/CAM1.CSI1_D1-")
			(pinfunction "CSI1_D1_N")
			(pintype "input")
		)
		(pad "J43" smd circle
			(at 10.4 -4.5 90)
			(size 0.5 0.5)
			(layers "F.Cu" "F.Mask" "F.Paste")
			(net 1 "GND")
			(pinfunction "GND")
			(pintype "passive")
		)
		(pad "J44" smd circle
			(at 11.3 -4.5 90)
			(size 0.5 0.5)
			(layers "F.Cu" "F.Mask" "F.Paste")
			(net 53 "/CSI/CAM3.CSI6_CLK+")
			(pinfunction "CSI6_CLK_P")
			(pintype "input")
		)
		(pad "J45" smd circle
			(at 12.2 -4.5 90)
			(size 0.5 0.5)
			(layers "F.Cu" "F.Mask" "F.Paste")
			(net 116 "/CSI/CAM3.CSI6_CLK-")
			(pinfunction "CSI6_CLK_N")
			(pintype "input")
		)
		(pad "J46" smd circle
			(at 13.1 -4.5 90)
			(size 0.5 0.5)
			(layers "F.Cu" "F.Mask" "F.Paste")
			(net 1 "GND")
			(pinfunction "GND")
			(pintype "passive")
		)
		(pad "J47" smd circle
			(at 14 -4.5 90)
			(size 0.5 0.5)
			(layers "F.Cu" "F.Mask" "F.Paste")
			(net 1223 "/SoM_IO2/DP1.TX2_C+")
			(pinfunction "DP1_D2_HDMI_D0_P")
			(pintype "output")
		)
		(pad "J48" smd circle
			(at 14.9 -4.5 90)
			(size 0.5 0.5)
			(layers "F.Cu" "F.Mask" "F.Paste")
			(net 1250 "/SoM_IO2/DP1.TX2_C-")
			(pinfunction "DP1_D2_HDMI_D0_N")
			(pintype "output")
		)
		(pad "J49" smd circle
			(at 15.8 -4.5 90)
			(size 0.5 0.5)
			(layers "F.Cu" "F.Mask" "F.Paste")
			(net 1 "GND")
			(pinfunction "GND")
			(pintype "passive")
		)
		(pad "J50" smd circle
			(at 16.7 -4.5 90)
			(size 0.5 0.5)
			(layers "F.Cu" "F.Mask" "F.Paste")
			(net 497 "unconnected-(J1E-HDMI_CEC-PadJ50)")
			(pinfunction "HDMI_CEC")
			(pintype "bidirectional+no_connect")
		)
		(pad "J51" smd circle
			(at 17.6 -4.5 90)
			(size 0.5 0.5)
			(layers "F.Cu" "F.Mask" "F.Paste")
			(net 723 "unconnected-(J1I-GPIO24-PadJ51)")
			(pinfunction "GPIO24")
			(pintype "bidirectional+no_connect")
		)
		(pad "J52" smd circle
			(at 18.5 -4.5 90)
			(size 0.5 0.5)
			(layers "F.Cu" "F.Mask" "F.Paste")
			(net 317 "/SoM_IO/I2C0_SCL_1V8")
			(pinfunction "I2C0_CLK")
			(pintype "bidirectional")
		)
	)
)
